# SCM (Grand Teton) — schematic netlist excerpt (pin names and nets, part order shuffled) for the footprints in the layout excerpt that follows; sources: Cadence DE-HDL packaged netlist, KiCad conversion of 12092022_DA0F0TMDCD0_F0T_Management_Board_D_brd_V3_OCP.brd

C14  Q_CAP  0.1UF 25V 10% X7R  pkg 0402  page 20 : A = P1V2_AUX ; B = GND
PC267  Q_CAP  22UF 4V 20% X6S  pkg 0805  page 56 : A = P1V0_AUX ; B = GND

(kicad_pcb
	(version 20260206)
	(generator "pcbnew")
	(generator_version "10.0")
	(general
		(thickness 1.6)
		(legacy_teardrops no)
	)
	(paper "A4")
	(title_block
		(title "12092022_DA0F0TMDCD0_F0T_Management_Board_D_brd_V3_OCP.brd")
		(comment 1 "Grand Teton / footprints 793-794 of 1440")
	)
	(layers
		(0 "F.Cu" signal "TOP")
		(4 "In1.Cu" signal "GND")
		(6 "In2.Cu" signal "IN1")
		(8 "In3.Cu" signal "GND1")
		(10 "In4.Cu" signal "IN2")
		(12 "In5.Cu" signal "VCC")
		(14 "In6.Cu" signal "VCC1")
		(16 "In7.Cu" signal "IN3")
		(18 "In8.Cu" signal "GND2")
		(20 "In9.Cu" signal "IN4")
		(22 "In10.Cu" signal "GND3")
		(2 "B.Cu" signal "BOTTOM")
		(9 "F.Adhes" user "F.Adhesive")
		(11 "B.Adhes" user "B.Adhesive")
		(13 "F.Paste" user "Package Geometry/Pastemask Top")
		(15 "B.Paste" user "Package Geometry/Pastemask Bottom")
		(5 "F.SilkS" user "Ref Des/Silkscreen Top")
		(7 "B.SilkS" user "Ref Des/Silkscreen Bottom")
		(1 "F.Mask" user "Board Geometry/Soldermask Top")
		(3 "B.Mask" user "Board Geometry/Soldermask Bottom")
		(17 "Dwgs.User" user "User.Drawings")
		(19 "Cmts.User" user "User.Comments")
		(21 "Eco1.User" user "User.Eco1")
		(23 "Eco2.User" user "User.Eco2")
		(25 "Edge.Cuts" user "Board Geometry/Outline")
		(27 "Margin" user)
		(31 "F.CrtYd" user "Package Geometry/Place Bound Top")
		(29 "B.CrtYd" user "Package Geometry/Place Bound Bottom")
		(35 "F.Fab" user "Ref Des/Assembly Top")
		(33 "B.Fab" user "Ref Des/Assembly Bottom")
	)
	(footprint ""
		(layer "B.Cu")
		(at 85.29955 -42.395394 180)
		(property "Reference" "C14"
			(at 0 0 0)
			(layer "B.SilkS")
			(hide yes)
			(effects
				(font
					(size 1.27 1.27)
				)
				(justify mirror)
			)
		)
		(property "Value" ""
			(at 0 0 0)
			(layer "B.Fab")
			(effects
				(font
					(size 1.27 1.27)
				)
				(justify mirror)
			)
		)
		(duplicate_pad_numbers_are_jumpers no)
		(fp_line
			(start 0.7874 0.4064)
			(end 0.7874 -0.4064)
			(stroke
				(width 0.1524)
				(type default)
			)
			(layer "B.SilkS")
		)
		(fp_line
			(start 0.7874 -0.4064)
			(end -0.7874 -0.4064)
			(stroke
				(width 0.1524)
				(type default)
			)
			(layer "B.SilkS")
		)
		(fp_line
			(start -0.7874 0.4064)
			(end 0.7874 0.4064)
			(stroke
				(width 0.1524)
				(type default)
			)
			(layer "B.SilkS")
		)
		(fp_line
			(start -0.7874 -0.4064)
			(end -0.7874 0.4064)
			(stroke
				(width 0.1524)
				(type default)
			)
			(layer "B.SilkS")
		)
		(fp_line
			(start 0.67945 0.3048)
			(end 0.67945 -0.305054)
			(stroke
				(width 0.1)
				(type default)
			)
			(layer "B.Fab")
		)
		(fp_line
			(start 0.67945 -0.305054)
			(end 0.12065 -0.305054)
			(stroke
				(width 0.1)
				(type default)
			)
			(layer "B.Fab")
		)
		(fp_line
			(start 0.12065 0.3048)
			(end 0.67945 0.3048)
			(stroke
				(width 0.1)
				(type default)
			)
			(layer "B.Fab")
		)
		(fp_line
			(start 0.12065 0.2794)
			(end 0.12065 0.3048)
			(stroke
				(width 0.1)
				(type default)
			)
			(layer "B.Fab")
		)
		(fp_line
			(start 0.12065 -0.2794)
			(end -0.12065 -0.2794)
			(stroke
				(width 0.1)
				(type default)
			)
			(layer "B.Fab")
		)
		(fp_line
			(start 0.12065 -0.305054)
			(end 0.12065 -0.2794)
			(stroke
				(width 0.1)
				(type default)
			)
			(layer "B.Fab")
		)
		(fp_line
			(start -0.120396 0.3048)
			(end -0.120396 0.2794)
			(stroke
				(width 0.1)
				(type default)
			)
			(layer "B.Fab")
		)
		(fp_line
			(start -0.120396 0.2794)
			(end 0.12065 0.2794)
			(stroke
				(width 0.1)
				(type default)
			)
			(layer "B.Fab")
		)
		(fp_line
			(start -0.12065 -0.2794)
			(end -0.12065 -0.3048)
			(stroke
				(width 0.1)
				(type default)
			)
			(layer "B.Fab")
		)
		(fp_line
			(start -0.12065 -0.3048)
			(end -0.67945 -0.3048)
			(stroke
				(width 0.1)
				(type default)
			)
			(layer "B.Fab")
		)
		(fp_line
			(start -0.67945 0.3048)
			(end -0.120396 0.3048)
			(stroke
				(width 0.1)
				(type default)
			)
			(layer "B.Fab")
		)
		(fp_line
			(start -0.67945 -0.3048)
			(end -0.67945 0.3048)
			(stroke
				(width 0.1)
				(type default)
			)
			(layer "B.Fab")
		)
		(pad "1" smd circle
			(at 0.40005 0)
			(size 0 0)
			(layers "B.Cu" "B.Mask" "B.Paste")
			(net "P1V2_AUX")
		)
		(pad "2" smd circle
			(at -0.40005 0)
			(size 0 0)
			(layers "B.Cu" "B.Mask" "B.Paste")
			(net "GND")
		)
	)
	(footprint ""
		(layer "B.Cu")
		(at 24.3078 -24.003 -90)
		(property "Reference" "PC267"
			(at 0 0 90)
			(layer "B.SilkS")
			(hide yes)
			(effects
				(font
					(size 1.27 1.27)
				)
				(justify mirror)
			)
		)
		(property "Value" ""
			(at 0 0 90)
			(layer "B.Fab")
			(effects
				(font
					(size 1.27 1.27)
				)
				(justify mirror)
			)
		)
		(duplicate_pad_numbers_are_jumpers no)
		(fp_line
			(start -1.651 0.8382)
			(end 1.651 0.8382)
			(stroke
				(width 0.1524)
				(type default)
			)
			(layer "B.SilkS")
		)
		(fp_line
			(start 0 0.8382)
			(end 0 -0.8382)
			(stroke
				(width 0.1524)
				(type default)
			)
			(layer "B.SilkS")
		)
		(fp_line
			(start 1.651 0.8382)
			(end 1.651 -0.8382)
			(stroke
				(width 0.1524)
				(type default)
			)
			(layer "B.SilkS")
		)
		(fp_line
			(start -1.651 -0.8382)
			(end -1.651 0.8382)
			(stroke
				(width 0.1524)
				(type default)
			)
			(layer "B.SilkS")
		)
		(fp_line
			(start 1.651 -0.8382)
			(end -1.651 -0.8382)
			(stroke
				(width 0.1524)
				(type default)
			)
			(layer "B.SilkS")
		)
		(fp_line
			(start -1.55956 0.7366)
			(end -1.55956 -0.7366)
			(stroke
				(width 0.1)
				(type default)
			)
			(layer "B.Fab")
		)
		(fp_line
			(start -1.524 0.7366)
			(end -1.55956 0.7366)
			(stroke
				(width 0.1)
				(type default)
			)
			(layer "B.Fab")
		)
		(fp_line
			(start 1.524 0.7366)
			(end -1.524 0.7366)
			(stroke
				(width 0.1)
				(type default)
			)
			(layer "B.Fab")
		)
		(fp_line
			(start 1.55956 0.7366)
			(end 1.524 0.7366)
			(stroke
				(width 0.1)
				(type default)
			)
			(layer "B.Fab")
		)
		(fp_line
			(start -1.55956 -0.7366)
			(end -1.524 -0.7366)
			(stroke
				(width 0.1)
				(type default)
			)
			(layer "B.Fab")
		)
		(fp_line
			(start -1.524 -0.7366)
			(end 1.524 -0.7366)
			(stroke
				(width 0.1)
				(type default)
			)
			(layer "B.Fab")
		)
		(fp_line
			(start 1.524 -0.7366)
			(end 1.55956 -0.7366)
			(stroke
				(width 0.1)
				(type default)
			)
			(layer "B.Fab")
		)
		(fp_line
			(start 1.55956 -0.7366)
			(end 1.55956 0.7366)
			(stroke
				(width 0.1)
				(type default)
			)
			(layer "B.Fab")
		)
		(pad "1" smd rect
			(at 0.94996 0 270)
			(size 1.1176 1.3716)
			(layers "B.Cu" "B.Mask" "B.Paste")
			(net "P1V0_AUX")
		)
		(pad "2" smd rect
			(at -0.94996 0 270)
			(size 1.1176 1.3716)
			(layers "B.Cu" "B.Mask" "B.Paste")
			(net "GND")
		)
	)
)
